(kicad_pcb
	(version 20260206)
	(generator "pcbnew")
	(generator_version "10.0")
	(general
		(thickness 1.6)
		(legacy_teardrops no)
	)
	(paper "A4")
	(title_block
		(title "03242023_DA0F0TMBIJ0_F0T_Motherboard_J_brd_V01_OCP.brd")
		(comment 1 "Grand Teton / footprints 4276-4283 of 6105")
	)
	(layers
		(0 "F.Cu" signal "TOP")
		(4 "In1.Cu" signal "GND")
		(6 "In2.Cu" signal "IN1")
		(8 "In3.Cu" signal "GND1")
		(10 "In4.Cu" signal "IN2")
		(12 "In5.Cu" signal "GND2")
		(14 "In6.Cu" signal "IN3")
		(16 "In7.Cu" signal "GND3")
		(18 "In8.Cu" signal "VCC")
		(20 "In9.Cu" signal "VCC1")
		(22 "In10.Cu" signal "GND4")
		(24 "In11.Cu" signal "IN4")
		(26 "In12.Cu" signal "GND5")
		(28 "In13.Cu" signal "IN5")
		(30 "In14.Cu" signal "GND6")
		(32 "In15.Cu" signal "IN6")
		(34 "In16.Cu" signal "GND7")
		(2 "B.Cu" signal "BOTTOM")
		(9 "F.Adhes" user "F.Adhesive")
		(11 "B.Adhes" user "B.Adhesive")
		(13 "F.Paste" user "Package Geometry/Pastemask Top")
		(15 "B.Paste" user "Package Geometry/Pastemask Bottom")
		(5 "F.SilkS" user "Ref Des/Silkscreen Top")
		(7 "B.SilkS" user "Ref Des/Silkscreen Bottom")
		(1 "F.Mask" user "Board Geometry/Soldermask Top")
		(3 "B.Mask" user "Board Geometry/Soldermask Bottom")
		(17 "Dwgs.User" user "User.Drawings")
		(19 "Cmts.User" user "User.Comments")
		(21 "Eco1.User" user "User.Eco1")
		(23 "Eco2.User" user "User.Eco2")
		(25 "Edge.Cuts" user "Board Geometry/Outline")
		(27 "Margin" user)
		(31 "F.CrtYd" user "Package Geometry/Place Bound Top")
		(29 "B.CrtYd" user "Package Geometry/Place Bound Bottom")
		(35 "F.Fab" user "Ref Des/Assembly Top")
		(33 "B.Fab" user "Ref Des/Assembly Bottom")
	)
	(footprint ""
		(layer "B.Cu")
		(at 47.650908 -193.25971 -90)
		(property "Reference" "R257"
			(at 0 0 90)
			(layer "B.SilkS")
			(hide yes)
			(effects
				(font
					(size 1.27 1.27)
				)
				(justify mirror)
			)
		)
		(property "Value" ""
			(at 0 0 90)
			(layer "B.Fab")
			(effects
				(font
					(size 1.27 1.27)
				)
				(justify mirror)
			)
		)
		(duplicate_pad_numbers_are_jumpers no)
		(fp_line
			(start -0.7874 0.4064)
			(end 0.7874 0.4064)
			(stroke
				(width 0.1524)
				(type default)
			)
			(layer "B.SilkS")
		)
		(fp_line
			(start 0.7874 0.4064)
			(end 0.7874 -0.4064)
			(stroke
				(width 0.1524)
				(type default)
			)
			(layer "B.SilkS")
		)
		(fp_line
			(start -0.7874 -0.4064)
			(end -0.7874 0.4064)
			(stroke
				(width 0.1524)
				(type default)
			)
			(layer "B.SilkS")
		)
		(fp_line
			(start 0.7874 -0.4064)
			(end -0.7874 -0.4064)
			(stroke
				(width 0.1524)
				(type default)
			)
			(layer "B.SilkS")
		)
		(fp_line
			(start -0.67945 0.3048)
			(end -0.120396 0.3048)
			(stroke
				(width 0.1)
				(type default)
			)
			(layer "B.Fab")
		)
		(fp_line
			(start -0.120396 0.3048)
			(end -0.120396 0.2794)
			(stroke
				(width 0.1)
				(type default)
			)
			(layer "B.Fab")
		)
		(fp_line
			(start 0.12065 0.3048)
			(end 0.67945 0.3048)
			(stroke
				(width 0.1)
				(type default)
			)
			(layer "B.Fab")
		)
		(fp_line
			(start 0.67945 0.3048)
			(end 0.67945 -0.305054)
			(stroke
				(width 0.1)
				(type default)
			)
			(layer "B.Fab")
		)
		(fp_line
			(start -0.120396 0.2794)
			(end 0.12065 0.2794)
			(stroke
				(width 0.1)
				(type default)
			)
			(layer "B.Fab")
		)
		(fp_line
			(start 0.12065 0.2794)
			(end 0.12065 0.3048)
			(stroke
				(width 0.1)
				(type default)
			)
			(layer "B.Fab")
		)
		(fp_line
			(start -0.12065 -0.2794)
			(end -0.12065 -0.3048)
			(stroke
				(width 0.1)
				(type default)
			)
			(layer "B.Fab")
		)
		(fp_line
			(start 0.12065 -0.2794)
			(end -0.12065 -0.2794)
			(stroke
				(width 0.1)
				(type default)
			)
			(layer "B.Fab")
		)
		(fp_line
			(start -0.67945 -0.3048)
			(end -0.67945 0.3048)
			(stroke
				(width 0.1)
				(type default)
			)
			(layer "B.Fab")
		)
		(fp_line
			(start -0.12065 -0.3048)
			(end -0.67945 -0.3048)
			(stroke
				(width 0.1)
				(type default)
			)
			(layer "B.Fab")
		)
		(fp_line
			(start 0.12065 -0.305054)
			(end 0.12065 -0.2794)
			(stroke
				(width 0.1)
				(type default)
			)
			(layer "B.Fab")
		)
		(fp_line
			(start 0.67945 -0.305054)
			(end 0.12065 -0.305054)
			(stroke
				(width 0.1)
				(type default)
			)
			(layer "B.Fab")
		)
		(pad "1" smd circle
			(at 0.40005 0 90)
			(size 0 0)
			(layers "B.Cu" "B.Mask" "B.Paste")
			(net "PVNN_TERM_CPU1")
		)
		(pad "2" smd circle
			(at -0.40005 0 90)
			(size 0 0)
			(layers "B.Cu" "B.Mask" "B.Paste")
			(net "FM_S3M_CPU1_LVC1_GPIO_4")
		)
	)
	(footprint ""
		(layer "B.Cu")
		(at 338.133182 -64.315848 90)
		(property "Reference" "C170"
			(at 0 0 90)
			(layer "B.SilkS")
			(hide yes)
			(effects
				(font
					(size 1.27 1.27)
				)
				(justify mirror)
			)
		)
		(property "Value" ""
			(at 0 0 90)
			(layer "B.Fab")
			(effects
				(font
					(size 1.27 1.27)
				)
				(justify mirror)
			)
		)
		(duplicate_pad_numbers_are_jumpers no)
		(fp_line
			(start 0.299974 -0.150114)
			(end -0.299974 -0.150114)
			(stroke
				(width 0.1)
				(type default)
			)
			(layer "B.Fab")
		)
		(fp_line
			(start -0.299974 -0.150114)
			(end -0.299974 0.150114)
			(stroke
				(width 0.1)
				(type default)
			)
			(layer "B.Fab")
		)
		(fp_line
			(start 0.299974 0.150114)
			(end 0.299974 -0.150114)
			(stroke
				(width 0.1)
				(type default)
			)
			(layer "B.Fab")
		)
		(fp_line
			(start -0.299974 0.150114)
			(end 0.299974 0.150114)
			(stroke
				(width 0.1)
				(type default)
			)
			(layer "B.Fab")
		)
		(pad "1" smd rect
			(at 0.2667 0 270)
			(size 0.3048 0.381)
			(layers "B.Cu" "B.Mask" "B.Paste")
			(net "DMI_CPU0_PCH_RX_C_DP<0>")
		)
		(pad "2" smd rect
			(at -0.2667 0 270)
			(size 0.3048 0.381)
			(layers "B.Cu" "B.Mask" "B.Paste")
			(net "DMI_CPU0_PCH_RX_DP<0>")
		)
	)
	(footprint ""
		(layer "B.Cu")
		(at 31.9024 -164.292788 180)
		(property "Reference" "PR410"
			(at 0 0 0)
			(layer "B.SilkS")
			(hide yes)
			(effects
				(font
					(size 1.27 1.27)
				)
				(justify mirror)
			)
		)
		(property "Value" ""
			(at 0 0 0)
			(layer "B.Fab")
			(effects
				(font
					(size 1.27 1.27)
				)
				(justify mirror)
			)
		)
		(duplicate_pad_numbers_are_jumpers no)
		(fp_line
			(start 0.7874 0.4064)
			(end 0.7874 -0.4064)
			(stroke
				(width 0.1524)
				(type default)
			)
			(layer "B.SilkS")
		)
		(fp_line
			(start 0.7874 -0.4064)
			(end -0.7874 -0.4064)
			(stroke
				(width 0.1524)
				(type default)
			)
			(layer "B.SilkS")
		)
		(fp_line
			(start -0.7874 0.4064)
			(end 0.7874 0.4064)
			(stroke
				(width 0.1524)
				(type default)
			)
			(layer "B.SilkS")
		)
		(fp_line
			(start -0.7874 -0.4064)
			(end -0.7874 0.4064)
			(stroke
				(width 0.1524)
				(type default)
			)
			(layer "B.SilkS")
		)
		(fp_line
			(start 0.67945 0.3048)
			(end 0.67945 -0.305054)
			(stroke
				(width 0.1)
				(type default)
			)
			(layer "B.Fab")
		)
		(fp_line
			(start 0.67945 -0.305054)
			(end 0.12065 -0.305054)
			(stroke
				(width 0.1)
				(type default)
			)
			(layer "B.Fab")
		)
		(fp_line
			(start 0.12065 0.3048)
			(end 0.67945 0.3048)
			(stroke
				(width 0.1)
				(type default)
			)
			(layer "B.Fab")
		)
		(fp_line
			(start 0.12065 0.2794)
			(end 0.12065 0.3048)
			(stroke
				(width 0.1)
				(type default)
			)
			(layer "B.Fab")
		)
		(fp_line
			(start 0.12065 -0.2794)
			(end -0.12065 -0.2794)
			(stroke
				(width 0.1)
				(type default)
			)
			(layer "B.Fab")
		)
		(fp_line
			(start 0.12065 -0.305054)
			(end 0.12065 -0.2794)
			(stroke
				(width 0.1)
				(type default)
			)
			(layer "B.Fab")
		)
		(fp_line
			(start -0.120396 0.3048)
			(end -0.120396 0.2794)
			(stroke
				(width 0.1)
				(type default)
			)
			(layer "B.Fab")
		)
		(fp_line
			(start -0.120396 0.2794)
			(end 0.12065 0.2794)
			(stroke
				(width 0.1)
				(type default)
			)
			(layer "B.Fab")
		)
		(fp_line
			(start -0.12065 -0.2794)
			(end -0.12065 -0.3048)
			(stroke
				(width 0.1)
				(type default)
			)
			(layer "B.Fab")
		)
		(fp_line
			(start -0.12065 -0.3048)
			(end -0.67945 -0.3048)
			(stroke
				(width 0.1)
				(type default)
			)
			(layer "B.Fab")
		)
		(fp_line
			(start -0.67945 0.3048)
			(end -0.120396 0.3048)
			(stroke
				(width 0.1)
				(type default)
			)
			(layer "B.Fab")
		)
		(fp_line
			(start -0.67945 -0.3048)
			(end -0.67945 0.3048)
			(stroke
				(width 0.1)
				(type default)
			)
			(layer "B.Fab")
		)
		(pad "1" smd circle
			(at 0.40005 0)
			(size 0 0)
			(layers "B.Cu" "B.Mask" "B.Paste")
			(net "PVCCD_HV_CPU1_ISYS_R")
		)
		(pad "2" smd circle
			(at -0.40005 0)
			(size 0 0)
			(layers "B.Cu" "B.Mask" "B.Paste")
			(net "PVCCD_HV_CPU1_NVDIMM_ISENSE")
		)
	)
	(footprint ""
		(layer "B.Cu")
		(at 340.406228 -62.056264 90)
		(property "Reference" "C165"
			(at 0 0 90)
			(layer "B.SilkS")
			(hide yes)
			(effects
				(font
					(size 1.27 1.27)
				)
				(justify mirror)
			)
		)
		(property "Value" ""
			(at 0 0 90)
			(layer "B.Fab")
			(effects
				(font
					(size 1.27 1.27)
				)
				(justify mirror)
			)
		)
		(duplicate_pad_numbers_are_jumpers no)
		(fp_line
			(start 0.299974 -0.150114)
			(end -0.299974 -0.150114)
			(stroke
				(width 0.1)
				(type default)
			)
			(layer "B.Fab")
		)
		(fp_line
			(start -0.299974 -0.150114)
			(end -0.299974 0.150114)
			(stroke
				(width 0.1)
				(type default)
			)
			(layer "B.Fab")
		)
		(fp_line
			(start 0.299974 0.150114)
			(end 0.299974 -0.150114)
			(stroke
				(width 0.1)
				(type default)
			)
			(layer "B.Fab")
		)
		(fp_line
			(start -0.299974 0.150114)
			(end 0.299974 0.150114)
			(stroke
				(width 0.1)
				(type default)
			)
			(layer "B.Fab")
		)
		(pad "1" smd rect
			(at 0.2667 0 270)
			(size 0.3048 0.381)
			(layers "B.Cu" "B.Mask" "B.Paste")
			(net "DMI_CPU0_PCH_RX_C_DN<2>")
		)
		(pad "2" smd rect
			(at -0.2667 0 270)
			(size 0.3048 0.381)
			(layers "B.Cu" "B.Mask" "B.Paste")
			(net "DMI_CPU0_PCH_RX_DN<2>")
		)
	)
	(footprint ""
		(layer "B.Cu")
		(at 151.99487 -13.762228 90)
		(property "Reference" "R2417"
			(at 0 0 90)
			(layer "B.SilkS")
			(hide yes)
			(effects
				(font
					(size 1.27 1.27)
				)
				(justify mirror)
			)
		)
		(property "Value" ""
			(at 0 0 90)
			(layer "B.Fab")
			(effects
				(font
					(size 1.27 1.27)
				)
				(justify mirror)
			)
		)
		(duplicate_pad_numbers_are_jumpers no)
		(fp_line
			(start 0.7874 -0.4064)
			(end -0.7874 -0.4064)
			(stroke
				(width 0.1524)
				(type default)
			)
			(layer "B.SilkS")
		)
		(fp_line
			(start -0.7874 -0.4064)
			(end -0.7874 0.4064)
			(stroke
				(width 0.1524)
				(type default)
			)
			(layer "B.SilkS")
		)
		(fp_line
			(start 0.7874 0.4064)
			(end 0.7874 -0.4064)
			(stroke
				(width 0.1524)
				(type default)
			)
			(layer "B.SilkS")
		)
		(fp_line
			(start -0.7874 0.4064)
			(end 0.7874 0.4064)
			(stroke
				(width 0.1524)
				(type default)
			)
			(layer "B.SilkS")
		)
		(fp_line
			(start 0.67945 -0.305054)
			(end 0.12065 -0.305054)
			(stroke
				(width 0.1)
				(type default)
			)
			(layer "B.Fab")
		)
		(fp_line
			(start 0.12065 -0.305054)
			(end 0.12065 -0.2794)
			(stroke
				(width 0.1)
				(type default)
			)
			(layer "B.Fab")
		)
		(fp_line
			(start -0.12065 -0.3048)
			(end -0.67945 -0.3048)
			(stroke
				(width 0.1)
				(type default)
			)
			(layer "B.Fab")
		)
		(fp_line
			(start -0.67945 -0.3048)
			(end -0.67945 0.3048)
			(stroke
				(width 0.1)
				(type default)
			)
			(layer "B.Fab")
		)
		(fp_line
			(start 0.12065 -0.2794)
			(end -0.12065 -0.2794)
			(stroke
				(width 0.1)
				(type default)
			)
			(layer "B.Fab")
		)
		(fp_line
			(start -0.12065 -0.2794)
			(end -0.12065 -0.3048)
			(stroke
				(width 0.1)
				(type default)
			)
			(layer "B.Fab")
		)
		(fp_line
			(start 0.12065 0.2794)
			(end 0.12065 0.3048)
			(stroke
				(width 0.1)
				(type default)
			)
			(layer "B.Fab")
		)
		(fp_line
			(start -0.120396 0.2794)
			(end 0.12065 0.2794)
			(stroke
				(width 0.1)
				(type default)
			)
			(layer "B.Fab")
		)
		(fp_line
			(start 0.67945 0.3048)
			(end 0.67945 -0.305054)
			(stroke
				(width 0.1)
				(type default)
			)
			(layer "B.Fab")
		)
		(fp_line
			(start 0.12065 0.3048)
			(end 0.67945 0.3048)
			(stroke
				(width 0.1)
				(type default)
			)
			(layer "B.Fab")
		)
		(fp_line
			(start -0.120396 0.3048)
			(end -0.120396 0.2794)
			(stroke
				(width 0.1)
				(type default)
			)
			(layer "B.Fab")
		)
		(fp_line
			(start -0.67945 0.3048)
			(end -0.120396 0.3048)
			(stroke
				(width 0.1)
				(type default)
			)
			(layer "B.Fab")
		)
		(pad "1" smd circle
			(at 0.40005 0 270)
			(size 0 0)
			(layers "B.Cu" "B.Mask" "B.Paste")
			(net "SMB_S3M_CPU_3V3AUX_SCL")
		)
		(pad "2" smd circle
			(at -0.40005 0 270)
			(size 0 0)
			(layers "B.Cu" "B.Mask" "B.Paste")
			(net "SMB_S3M_CPU_3V3AUX_SCL_R0")
		)
	)
	(footprint ""
		(layer "B.Cu")
		(at 178.55565 -118.575328)
		(property "Reference" "C1902"
			(at 0 0 0)
			(layer "B.SilkS")
			(hide yes)
			(effects
				(font
					(size 1.27 1.27)
				)
				(justify mirror)
			)
		)
		(property "Value" ""
			(at 0 0 0)
			(layer "B.Fab")
			(effects
				(font
					(size 1.27 1.27)
				)
				(justify mirror)
			)
		)
		(duplicate_pad_numbers_are_jumpers no)
		(fp_line
			(start -0.69215 -0.2921)
			(end -0.69215 0.2921)
			(stroke
				(width 0.1524)
				(type default)
			)
			(layer "B.SilkS")
		)
		(fp_line
			(start -0.69215 0.2921)
			(end 0.69215 0.2921)
			(stroke
				(width 0.1524)
				(type default)
			)
			(layer "B.SilkS")
		)
		(fp_line
			(start 0.69215 -0.2921)
			(end -0.69215 -0.2921)
			(stroke
				(width 0.1524)
				(type default)
			)
			(layer "B.SilkS")
		)
		(fp_line
			(start 0.69215 0.2921)
			(end 0.69215 -0.2921)
			(stroke
				(width 0.1524)
				(type default)
			)
			(layer "B.SilkS")
		)
		(fp_line
			(start -0.51435 -0.2794)
			(end -0.51435 0.2794)
			(stroke
				(width 0.1)
				(type default)
			)
			(layer "B.Fab")
		)
		(fp_line
			(start -0.51435 0.2794)
			(end 0.51435 0.2794)
			(stroke
				(width 0.1)
				(type default)
			)
			(layer "B.Fab")
		)
		(fp_line
			(start 0.51435 -0.2794)
			(end -0.51435 -0.2794)
			(stroke
				(width 0.1)
				(type default)
			)
			(layer "B.Fab")
		)
		(fp_line
			(start 0.51435 0.2794)
			(end 0.51435 -0.2794)
			(stroke
				(width 0.1)
				(type default)
			)
			(layer "B.Fab")
		)
		(pad "1" smd circle
			(at 0.40005 0 180)
			(size 0 0)
			(layers "B.Cu" "B.Mask" "B.Paste")
			(net "P3V3_AUX_FPGA_VCCIO1")
		)
		(pad "2" smd circle
			(at -0.40005 0 180)
			(size 0 0)
			(layers "B.Cu" "B.Mask" "B.Paste")
			(net "GND")
		)
		(zone
			(layer "B.Cu")
			(hatch none 0.5)
			(connect_pads
				(clearance 0)
			)
			(min_thickness 0.25)
			(keepout
				(tracks not_allowed)
				(vias allowed)
				(pads allowed)
				(copperpour not_allowed)
				(footprints allowed)
			)
			(placement
				(enabled no)
				(sheetname "")
			)
			(fill
				(thermal_gap 0.5)
				(thermal_bridge_width 0.5)
				(island_removal_mode 0)
			)
			(polygon
				(pts
					(xy 178.74615 -118.487698) (xy 178.65471 -118.429532) (xy 178.45532 -118.429532) (xy 178.36515 -118.487698)
					(xy 178.36515 -118.662958) (xy 178.45532 -118.721378) (xy 178.65471 -118.721378) (xy 178.74615 -118.663212)
				)
			)
		)
	)
	(footprint ""
		(layer "B.Cu")
		(at 46.634908 -193.25971 -90)
		(property "Reference" "R256"
			(at 0 0 90)
			(layer "B.SilkS")
			(hide yes)
			(effects
				(font
					(size 1.27 1.27)
				)
				(justify mirror)
			)
		)
		(property "Value" ""
			(at 0 0 90)
			(layer "B.Fab")
			(effects
				(font
					(size 1.27 1.27)
				)
				(justify mirror)
			)
		)
		(duplicate_pad_numbers_are_jumpers no)
		(fp_line
			(start -0.7874 0.4064)
			(end 0.7874 0.4064)
			(stroke
				(width 0.1524)
				(type default)
			)
			(layer "B.SilkS")
		)
		(fp_line
			(start 0.7874 0.4064)
			(end 0.7874 -0.4064)
			(stroke
				(width 0.1524)
				(type default)
			)
			(layer "B.SilkS")
		)
		(fp_line
			(start -0.7874 -0.4064)
			(end -0.7874 0.4064)
			(stroke
				(width 0.1524)
				(type default)
			)
			(layer "B.SilkS")
		)
		(fp_line
			(start 0.7874 -0.4064)
			(end -0.7874 -0.4064)
			(stroke
				(width 0.1524)
				(type default)
			)
			(layer "B.SilkS")
		)
		(fp_line
			(start -0.67945 0.3048)
			(end -0.120396 0.3048)
			(stroke
				(width 0.1)
				(type default)
			)
			(layer "B.Fab")
		)
		(fp_line
			(start -0.120396 0.3048)
			(end -0.120396 0.2794)
			(stroke
				(width 0.1)
				(type default)
			)
			(layer "B.Fab")
		)
		(fp_line
			(start 0.12065 0.3048)
			(end 0.67945 0.3048)
			(stroke
				(width 0.1)
				(type default)
			)
			(layer "B.Fab")
		)
		(fp_line
			(start 0.67945 0.3048)
			(end 0.67945 -0.305054)
			(stroke
				(width 0.1)
				(type default)
			)
			(layer "B.Fab")
		)
		(fp_line
			(start -0.120396 0.2794)
			(end 0.12065 0.2794)
			(stroke
				(width 0.1)
				(type default)
			)
			(layer "B.Fab")
		)
		(fp_line
			(start 0.12065 0.2794)
			(end 0.12065 0.3048)
			(stroke
				(width 0.1)
				(type default)
			)
			(layer "B.Fab")
		)
		(fp_line
			(start -0.12065 -0.2794)
			(end -0.12065 -0.3048)
			(stroke
				(width 0.1)
				(type default)
			)
			(layer "B.Fab")
		)
		(fp_line
			(start 0.12065 -0.2794)
			(end -0.12065 -0.2794)
			(stroke
				(width 0.1)
				(type default)
			)
			(layer "B.Fab")
		)
		(fp_line
			(start -0.67945 -0.3048)
			(end -0.67945 0.3048)
			(stroke
				(width 0.1)
				(type default)
			)
			(layer "B.Fab")
		)
		(fp_line
			(start -0.12065 -0.3048)
			(end -0.67945 -0.3048)
			(stroke
				(width 0.1)
				(type default)
			)
			(layer "B.Fab")
		)
		(fp_line
			(start 0.12065 -0.305054)
			(end 0.12065 -0.2794)
			(stroke
				(width 0.1)
				(type default)
			)
			(layer "B.Fab")
		)
		(fp_line
			(start 0.67945 -0.305054)
			(end 0.12065 -0.305054)
			(stroke
				(width 0.1)
				(type default)
			)
			(layer "B.Fab")
		)
		(pad "1" smd circle
			(at 0.40005 0 90)
			(size 0 0)
			(layers "B.Cu" "B.Mask" "B.Paste")
			(net "PVNN_TERM_CPU1")
		)
		(pad "2" smd circle
			(at -0.40005 0 90)
			(size 0 0)
			(layers "B.Cu" "B.Mask" "B.Paste")
			(net "FM_S3M_CPU1_LVC1_GPIO_1")
		)
	)
	(footprint ""
		(layer "B.Cu")
		(at 312.989214 -250.785376 90)
		(property "Reference" "C529"
			(at 0 0 90)
			(layer "B.SilkS")
			(hide yes)
			(effects
				(font
					(size 1.27 1.27)
				)
				(justify mirror)
			)
		)
		(property "Value" ""
			(at 0 0 90)
			(layer "B.Fab")
			(effects
				(font
					(size 1.27 1.27)
				)
				(justify mirror)
			)
		)
		(duplicate_pad_numbers_are_jumpers no)
		(fp_line
			(start 1.524 -0.762)
			(end -1.524 -0.762)
			(stroke
				(width 0.1524)
				(type default)
			)
			(layer "B.SilkS")
		)
		(fp_line
			(start -1.524 -0.762)
			(end -1.524 0.762)
			(stroke
				(width 0.1524)
				(type default)
			)
			(layer "B.SilkS")
		)
		(fp_line
			(start 1.524 0.762)
			(end 1.524 -0.762)
			(stroke
				(width 0.1524)
				(type default)
			)
			(layer "B.SilkS")
		)
		(fp_line
			(start -1.524 0.762)
			(end 1.524 0.762)
			(stroke
				(width 0.1524)
				(type default)
			)
			(layer "B.SilkS")
		)
		(fp_line
			(start 1.1049 -0.724916)
			(end 1.1049 0.724916)
			(stroke
				(width 0.1)
				(type default)
			)
			(layer "B.Fab")
		)
		(fp_line
			(start -1.1049 -0.724916)
			(end 1.1049 -0.724916)
			(stroke
				(width 0.1)
				(type default)
			)
			(layer "B.Fab")
		)
		(fp_line
			(start 1.1049 0.724916)
			(end -1.1049 0.724916)
			(stroke
				(width 0.1)
				(type default)
			)
			(layer "B.Fab")
		)
		(fp_line
			(start -1.1049 0.724916)
			(end -1.1049 -0.724916)
			(stroke
				(width 0.1)
				(type default)
			)
			(layer "B.Fab")
		)
		(pad "1" smd rect
			(at 0.889 0 90)
			(size 1.016 1.27)
			(layers "B.Cu" "B.Mask" "B.Paste")
			(net "PVCCFA_EHV_FIVRA_CPU0")
		)
		(pad "2" smd rect
			(at -0.889 0 90)
			(size 1.016 1.27)
			(layers "B.Cu" "B.Mask" "B.Paste")
			(net "GND")
		)
	)
)
